FILE_TYPE = CONNECTIVITY;
{Allegro Design Entry HDL 17.4-2019 S026 (4007227) 1/17/2022}
"PAGE_NUMBER" = 347;
0"NC";
END.
